# T6G (Grand Teton) — schematic netlist excerpt (pin names and nets, part order shuffled) for the footprints in the layout excerpt that follows; sources: Cadence DE-HDL packaged netlist, KiCad conversion of 04192023_DAF0TMB3IC0_F0TG_MB_C_brd_V02_OCP.brd

X8005  TP_TDR_4P_FTS  TP_TDR_4P_DIP EMPTY  pkg TH  page 260
  S1  = TDR_DIFF_85_IN4_DP
  P1  = T1_GND
  P2  = T1_GND
  S2  = TDR_DIFF_85_IN4_DN

R833  Q_RES  0 5% CHIP  pkg 0201LF  page 185 : A = SMB_RT_CPU0_P2_ROM_MUX_2D_R_SCL ; B = SMB_RT_CPU0_P2_ROM_MUX_2D_SCL
PC565_4  Q_CAP  22UF 4V 20% X6S  pkg C0805  page 195 : A = PVDDCR_CPU0_P0 ; B = GND

(kicad_pcb
	(version 20260206)
	(generator "pcbnew")
	(generator_version "10.0")
	(general
		(thickness 1.6)
		(legacy_teardrops no)
	)
	(paper "A4")
	(title_block
		(title "04192023_DAF0TMB3IC0_F0TG_MB_C_brd_V02_OCP.brd")
		(comment 1 "Grand Teton / footprints 5649-5651 of 8354")
	)
	(layers
		(0 "F.Cu" signal "TOP")
		(4 "In1.Cu" signal "GND")
		(6 "In2.Cu" signal "IN1")
		(8 "In3.Cu" signal "GND1")
		(10 "In4.Cu" signal "IN2")
		(12 "In5.Cu" signal "GND2")
		(14 "In6.Cu" signal "IN3")
		(16 "In7.Cu" signal "GND3")
		(18 "In8.Cu" signal "VCC")
		(20 "In9.Cu" signal "VCC1")
		(22 "In10.Cu" signal "GND4")
		(24 "In11.Cu" signal "IN4")
		(26 "In12.Cu" signal "GND5")
		(28 "In13.Cu" signal "IN5")
		(30 "In14.Cu" signal "GND6")
		(32 "In15.Cu" signal "IN6")
		(34 "In16.Cu" signal "GND7")
		(2 "B.Cu" signal "BOTTOM")
		(9 "F.Adhes" user "F.Adhesive")
		(11 "B.Adhes" user "B.Adhesive")
		(13 "F.Paste" user "Package Geometry/Pastemask Top")
		(15 "B.Paste" user "Package Geometry/Pastemask Bottom")
		(5 "F.SilkS" user "Ref Des/Silkscreen Top")
		(7 "B.SilkS" user "Ref Des/Silkscreen Bottom")
		(1 "F.Mask" user "Board Geometry/Soldermask Top")
		(3 "B.Mask" user "Board Geometry/Soldermask Bottom")
		(17 "Dwgs.User" user "User.Drawings")
		(19 "Cmts.User" user "User.Comments")
		(21 "Eco1.User" user "User.Eco1")
		(23 "Eco2.User" user "User.Eco2")
		(25 "Edge.Cuts" user "Board Geometry/Outline")
		(27 "Margin" user)
		(31 "F.CrtYd" user "Package Geometry/Place Bound Top")
		(29 "B.CrtYd" user "Package Geometry/Place Bound Bottom")
		(35 "F.Fab" user "Ref Des/Assembly Top")
		(33 "B.Fab" user "Ref Des/Assembly Bottom")
	)
	(footprint ""
		(layer "B.Cu")
		(at 514.718808 7.526274 90)
		(property "Reference" "X8005"
			(at 0.93726 -1.53035 270)
			(unlocked yes)
			(layer "B.SilkS")
			(effects
				(font
					(size 0.7874 0.5842)
					(thickness 0.1524)
				)
				(justify left mirror)
			)
		)
		(property "Value" ""
			(at 0 0 90)
			(layer "B.Fab")
			(effects
				(font
					(size 1.27 1.27)
				)
				(justify mirror)
			)
		)
		(property "Device Type" "TP_TDR_4P_FTS_TH-TP_TDR_4P_DIP,EMPTY,TP15"
			(at -1.30175 1.27 0)
			(unlocked yes)
			(layer "B.Fab")
			(hide yes)
			(effects
				(font
					(size 0.635 0.4064)
					(thickness 0.1524)
				)
				(justify mirror)
			)
		)
		(property "User Part Number" "N_A"
			(at -1.30175 1.27 0)
			(unlocked yes)
			(layer "Cmts.User")
			(hide yes)
			(effects
				(font
					(size 0.635 0.4064)
					(thickness 0.1524)
				)
				(justify mirror)
			)
		)
		(duplicate_pad_numbers_are_jumpers no)
		(fp_line
			(start 0 -1.27)
			(end 0 -0.635)
			(stroke
				(width 0.1524)
				(type default)
			)
			(layer "B.SilkS")
		)
		(fp_line
			(start -2.54 -1.27)
			(end 0 -1.27)
			(stroke
				(width 0.1524)
				(type default)
			)
			(layer "B.SilkS")
		)
		(fp_line
			(start -2.54 -1.1303)
			(end -2.54 -1.27)
			(stroke
				(width 0.1524)
				(type default)
			)
			(layer "B.SilkS")
		)
		(fp_line
			(start 0 0.635)
			(end 0 1.905)
			(stroke
				(width 0.1524)
				(type default)
			)
			(layer "B.SilkS")
		)
		(fp_line
			(start -2.54 1.4097)
			(end -2.54 1.1303)
			(stroke
				(width 0.1524)
				(type default)
			)
			(layer "B.SilkS")
		)
		(fp_line
			(start 0 3.175)
			(end 0 3.81)
			(stroke
				(width 0.1524)
				(type default)
			)
			(layer "B.SilkS")
		)
		(fp_line
			(start 0 3.81)
			(end -2.54 3.81)
			(stroke
				(width 0.1524)
				(type default)
			)
			(layer "B.SilkS")
		)
		(fp_line
			(start -2.54 3.81)
			(end -2.54 3.6703)
			(stroke
				(width 0.1524)
				(type default)
			)
			(layer "B.SilkS")
		)
		(fp_poly
			(pts
				(xy 0.761746 0) (xy 2.285746 -0.762) (xy 2.285746 0.762)
			)
			(stroke
				(width 0)
				(type default)
			)
			(fill yes)
			(layer "B.SilkS")
		)
		(fp_line
			(start 0 -1.27)
			(end 0 3.81)
			(stroke
				(width 0.1)
				(type default)
			)
			(layer "B.Fab")
		)
		(fp_line
			(start -2.54 -1.27)
			(end 0 -1.27)
			(stroke
				(width 0.1)
				(type default)
			)
			(layer "B.Fab")
		)
		(fp_line
			(start 0 3.81)
			(end -2.54 3.81)
			(stroke
				(width 0.1)
				(type default)
			)
			(layer "B.Fab")
		)
		(fp_line
			(start -2.54 3.81)
			(end -2.54 -1.27)
			(stroke
				(width 0.1)
				(type default)
			)
			(layer "B.Fab")
		)
		(fp_poly
			(pts
				(xy 0.761746 0) (xy 2.285746 -0.762) (xy 2.285746 0.762)
			)
			(stroke
				(width 0)
				(type default)
			)
			(fill yes)
			(layer "B.Fab")
		)
		(pad "1" thru_hole circle
			(at 0 0 270)
			(size 1.0033 1.0033)
			(drill 0.249936)
			(layers "*.Cu" "*.Mask")
			(remove_unused_layers no)
			(net "TDR_DIFF_85_IN4_DP")
			(clearance 0.10795)
			(padstack
				(mode front_inner_back)
				(layer "Inner"
					(shape circle)
					(size 0.8001 0.8001)
					(clearance 0.1524)
				)
				(layer "B.Cu"
					(shape circle)
					(size 1.0033 1.0033)
					(thermal_gap 0.10795)
					(clearance 0.10795)
				)
			)
		)
		(pad "2" thru_hole circle
			(at -2.54 0 270)
			(size 1.9939 1.9939)
			(drill 0.249936)
			(layers "*.Cu" "*.Mask")
			(remove_unused_layers no)
			(net "T1_GND")
			(clearance 0.10795)
			(padstack
				(mode front_inner_back)
				(layer "Inner"
					(shape circle)
					(size 0.8001 0.8001)
					(clearance 0.1524)
				)
				(layer "B.Cu"
					(shape circle)
					(size 1.9939 1.9939)
					(thermal_gap 0.10795)
					(clearance 0.10795)
				)
			)
		)
		(pad "3" thru_hole circle
			(at -2.54 2.54 270)
			(size 1.9939 1.9939)
			(drill 0.249936)
			(layers "*.Cu" "*.Mask")
			(remove_unused_layers no)
			(net "T1_GND")
			(clearance 0.10795)
			(padstack
				(mode front_inner_back)
				(layer "Inner"
					(shape circle)
					(size 0.8001 0.8001)
					(clearance 0.1524)
				)
				(layer "B.Cu"
					(shape circle)
					(size 1.9939 1.9939)
					(thermal_gap 0.10795)
					(clearance 0.10795)
				)
			)
		)
		(pad "4" thru_hole circle
			(at 0 2.54 270)
			(size 1.0033 1.0033)
			(drill 0.249936)
			(layers "*.Cu" "*.Mask")
			(remove_unused_layers no)
			(net "TDR_DIFF_85_IN4_DN")
			(clearance 0.10795)
			(padstack
				(mode front_inner_back)
				(layer "Inner"
					(shape circle)
					(size 0.8001 0.8001)
					(clearance 0.1524)
				)
				(layer "B.Cu"
					(shape circle)
					(size 1.0033 1.0033)
					(thermal_gap 0.10795)
					(clearance 0.10795)
				)
			)
		)
	)
	(footprint ""
		(layer "B.Cu")
		(at 385.3942 -191.33058 90)
		(property "Reference" "PC565_4"
			(at 0 0 90)
			(layer "B.SilkS")
			(hide yes)
			(effects
				(font
					(size 1.27 1.27)
				)
				(justify mirror)
			)
		)
		(property "Value" ""
			(at 0 0 90)
			(layer "B.Fab")
			(effects
				(font
					(size 1.27 1.27)
				)
				(justify mirror)
			)
		)
		(duplicate_pad_numbers_are_jumpers no)
		(fp_line
			(start 1.524 -0.762)
			(end -1.524 -0.762)
			(stroke
				(width 0.1524)
				(type default)
			)
			(layer "B.SilkS")
		)
		(fp_line
			(start -1.524 -0.762)
			(end -1.524 0.762)
			(stroke
				(width 0.1524)
				(type default)
			)
			(layer "B.SilkS")
		)
		(fp_line
			(start 1.524 0.762)
			(end 1.524 -0.762)
			(stroke
				(width 0.1524)
				(type default)
			)
			(layer "B.SilkS")
		)
		(fp_line
			(start -1.524 0.762)
			(end 1.524 0.762)
			(stroke
				(width 0.1524)
				(type default)
			)
			(layer "B.SilkS")
		)
		(fp_line
			(start 1.1049 -0.724916)
			(end 1.1049 0.724916)
			(stroke
				(width 0.1)
				(type default)
			)
			(layer "B.Fab")
		)
		(fp_line
			(start -1.1049 -0.724916)
			(end 1.1049 -0.724916)
			(stroke
				(width 0.1)
				(type default)
			)
			(layer "B.Fab")
		)
		(fp_line
			(start 1.1049 0.724916)
			(end -1.1049 0.724916)
			(stroke
				(width 0.1)
				(type default)
			)
			(layer "B.Fab")
		)
		(fp_line
			(start -1.1049 0.724916)
			(end -1.1049 -0.724916)
			(stroke
				(width 0.1)
				(type default)
			)
			(layer "B.Fab")
		)
		(pad "1" smd rect
			(at 0.889 0 90)
			(size 1.016 1.27)
			(layers "B.Cu" "B.Mask" "B.Paste")
			(net "PVDDCR_CPU0_P0")
		)
		(pad "2" smd rect
			(at -0.889 0 90)
			(size 1.016 1.27)
			(layers "B.Cu" "B.Mask" "B.Paste")
			(net "GND")
		)
	)
	(footprint ""
		(layer "B.Cu")
		(at 255.905 -334.01 180)
		(property "Reference" "R833"
			(at 0 0 0)
			(layer "B.SilkS")
			(hide yes)
			(effects
				(font
					(size 1.27 1.27)
				)
				(justify mirror)
			)
		)
		(property "Value" ""
			(at 0 0 0)
			(layer "B.Fab")
			(effects
				(font
					(size 1.27 1.27)
				)
				(justify mirror)
			)
		)
		(duplicate_pad_numbers_are_jumpers no)
		(fp_line
			(start 0.32512 0.175006)
			(end 0.32512 -0.175006)
			(stroke
				(width 0.1)
				(type default)
			)
			(layer "B.Fab")
		)
		(fp_line
			(start 0.32512 -0.175006)
			(end -0.32512 -0.175006)
			(stroke
				(width 0.1)
				(type default)
			)
			(layer "B.Fab")
		)
		(fp_line
			(start -0.32512 0.175006)
			(end 0.32512 0.175006)
			(stroke
				(width 0.1)
				(type default)
			)
			(layer "B.Fab")
		)
		(fp_line
			(start -0.32512 -0.175006)
			(end -0.32512 0.175006)
			(stroke
				(width 0.1)
				(type default)
			)
			(layer "B.Fab")
		)
		(pad "1" smd rect
			(at 0.2667 0)
			(size 0.3048 0.381)
			(layers "B.Cu" "B.Mask" "B.Paste")
			(net "SMB_RT_CPU0_P2_ROM_MUX_2D_R_SCL")
		)
		(pad "2" smd rect
			(at -0.2667 0 180)
			(size 0.3048 0.381)
			(layers "B.Cu" "B.Mask" "B.Paste")
			(net "SMB_RT_CPU0_P2_ROM_MUX_2D_SCL")
		)
	)
)
